(kicad_pcb
	(version 20260206)
	(generator "pcbnew")
	(generator_version "10.0")
	(general
		(thickness 1.6)
		(legacy_teardrops no)
	)
	(paper "A4")
	(title_block
		(title "01162023_DA0F0TEBIF0_F0T_Expander_BD_F_brd_V02_OCP.brd")
		(comment 1 "Grand Teton / footprints 6856-6862 of 9728")
	)
	(layers
		(0 "F.Cu" signal "TOP")
		(4 "In1.Cu" signal "GND")
		(6 "In2.Cu" signal "VCC")
		(8 "In3.Cu" signal "VCC1")
		(10 "In4.Cu" signal "GND1")
		(12 "In5.Cu" signal "IN1")
		(14 "In6.Cu" signal "GND2")
		(16 "In7.Cu" signal "IN2")
		(18 "In8.Cu" signal "GND3")
		(20 "In9.Cu" signal "IN3")
		(22 "In10.Cu" signal "GND4")
		(24 "In11.Cu" signal "IN4")
		(26 "In12.Cu" signal "GND5")
		(28 "In13.Cu" signal "IN5")
		(30 "In14.Cu" signal "GND6")
		(32 "In15.Cu" signal "IN6")
		(34 "In16.Cu" signal "GND7")
		(2 "B.Cu" signal "BOTTOM")
		(9 "F.Adhes" user "F.Adhesive")
		(11 "B.Adhes" user "B.Adhesive")
		(13 "F.Paste" user "Package Geometry/Pastemask Top")
		(15 "B.Paste" user "Package Geometry/Pastemask Bottom")
		(5 "F.SilkS" user "Ref Des/Silkscreen Top")
		(7 "B.SilkS" user "Ref Des/Silkscreen Bottom")
		(1 "F.Mask" user "Board Geometry/Soldermask Top")
		(3 "B.Mask" user "Board Geometry/Soldermask Bottom")
		(17 "Dwgs.User" user "User.Drawings")
		(19 "Cmts.User" user "User.Comments")
		(21 "Eco1.User" user "User.Eco1")
		(23 "Eco2.User" user "User.Eco2")
		(25 "Edge.Cuts" user "Board Geometry/Outline")
		(27 "Margin" user)
		(31 "F.CrtYd" user "Package Geometry/Place Bound Top")
		(29 "B.CrtYd" user "Package Geometry/Place Bound Bottom")
		(35 "F.Fab" user "Ref Des/Assembly Top")
		(33 "B.Fab" user "Ref Des/Assembly Bottom")
	)
	(footprint ""
		(layer "F.Cu")
		(at 142.926308 -350.098614 90)
		(property "Reference" "C2259"
			(at 0 0 90)
			(layer "F.SilkS")
			(hide yes)
			(effects
				(font
					(size 1.27 1.27)
				)
			)
		)
		(property "Value" ""
			(at 0 0 90)
			(layer "F.Fab")
			(effects
				(font
					(size 1.27 1.27)
				)
			)
		)
		(duplicate_pad_numbers_are_jumpers no)
		(fp_line
			(start 0.299974 -0.150114)
			(end 0.299974 0.150114)
			(stroke
				(width 0.1)
				(type default)
			)
			(layer "F.Fab")
		)
		(fp_line
			(start -0.299974 -0.150114)
			(end 0.299974 -0.150114)
			(stroke
				(width 0.1)
				(type default)
			)
			(layer "F.Fab")
		)
		(fp_line
			(start 0.299974 0.150114)
			(end -0.299974 0.150114)
			(stroke
				(width 0.1)
				(type default)
			)
			(layer "F.Fab")
		)
		(fp_line
			(start -0.299974 0.150114)
			(end -0.299974 -0.150114)
			(stroke
				(width 0.1)
				(type default)
			)
			(layer "F.Fab")
		)
		(pad "1" smd rect
			(at -0.2667 0 90)
			(size 0.3048 0.381)
			(layers "F.Cu" "F.Mask" "F.Paste")
			(net "P5E_PEX1_STN5_TX_DP<87>")
		)
		(pad "2" smd rect
			(at 0.2667 0 90)
			(size 0.3048 0.381)
			(layers "F.Cu" "F.Mask" "F.Paste")
			(net "P5E_PEX1_STN5_TX_C_DP<87>")
		)
	)
	(footprint ""
		(layer "F.Cu")
		(at 26.243788 -42.84091)
		(property "Reference" "R505"
			(at 0 0 0)
			(layer "F.SilkS")
			(hide yes)
			(effects
				(font
					(size 1.27 1.27)
				)
			)
		)
		(property "Value" ""
			(at 0 0 0)
			(layer "F.Fab")
			(effects
				(font
					(size 1.27 1.27)
				)
			)
		)
		(duplicate_pad_numbers_are_jumpers no)
		(fp_line
			(start -0.7874 -0.4064)
			(end 0.7874 -0.4064)
			(stroke
				(width 0.1524)
				(type default)
			)
			(layer "F.SilkS")
		)
		(fp_line
			(start -0.7874 0.4064)
			(end -0.7874 -0.4064)
			(stroke
				(width 0.1524)
				(type default)
			)
			(layer "F.SilkS")
		)
		(fp_line
			(start 0.7874 -0.4064)
			(end 0.7874 0.4064)
			(stroke
				(width 0.1524)
				(type default)
			)
			(layer "F.SilkS")
		)
		(fp_line
			(start 0.7874 0.4064)
			(end -0.7874 0.4064)
			(stroke
				(width 0.1524)
				(type default)
			)
			(layer "F.SilkS")
		)
		(fp_line
			(start -0.67945 -0.305054)
			(end -0.12065 -0.305054)
			(stroke
				(width 0.1)
				(type default)
			)
			(layer "F.Fab")
		)
		(fp_line
			(start -0.67945 0.3048)
			(end -0.67945 -0.305054)
			(stroke
				(width 0.1)
				(type default)
			)
			(layer "F.Fab")
		)
		(fp_line
			(start -0.12065 -0.305054)
			(end -0.12065 -0.2794)
			(stroke
				(width 0.1)
				(type default)
			)
			(layer "F.Fab")
		)
		(fp_line
			(start -0.12065 -0.2794)
			(end 0.12065 -0.2794)
			(stroke
				(width 0.1)
				(type default)
			)
			(layer "F.Fab")
		)
		(fp_line
			(start -0.12065 0.2794)
			(end -0.12065 0.3048)
			(stroke
				(width 0.1)
				(type default)
			)
			(layer "F.Fab")
		)
		(fp_line
			(start -0.12065 0.3048)
			(end -0.67945 0.3048)
			(stroke
				(width 0.1)
				(type default)
			)
			(layer "F.Fab")
		)
		(fp_line
			(start 0.120396 0.2794)
			(end -0.12065 0.2794)
			(stroke
				(width 0.1)
				(type default)
			)
			(layer "F.Fab")
		)
		(fp_line
			(start 0.120396 0.3048)
			(end 0.120396 0.2794)
			(stroke
				(width 0.1)
				(type default)
			)
			(layer "F.Fab")
		)
		(fp_line
			(start 0.12065 -0.3048)
			(end 0.67945 -0.3048)
			(stroke
				(width 0.1)
				(type default)
			)
			(layer "F.Fab")
		)
		(fp_line
			(start 0.12065 -0.2794)
			(end 0.12065 -0.3048)
			(stroke
				(width 0.1)
				(type default)
			)
			(layer "F.Fab")
		)
		(fp_line
			(start 0.67945 -0.3048)
			(end 0.67945 0.3048)
			(stroke
				(width 0.1)
				(type default)
			)
			(layer "F.Fab")
		)
		(fp_line
			(start 0.67945 0.3048)
			(end 0.120396 0.3048)
			(stroke
				(width 0.1)
				(type default)
			)
			(layer "F.Fab")
		)
		(pad "1" smd circle
			(at -0.40005 0)
			(size 0 0)
			(layers "F.Cu" "F.Mask" "F.Paste")
			(net "SSD0_ADC_A1")
		)
		(pad "2" smd circle
			(at 0.40005 0)
			(size 0 0)
			(layers "F.Cu" "F.Mask" "F.Paste")
			(net "P3V3_AUX")
		)
	)
	(footprint ""
		(layer "F.Cu")
		(at 214.373968 -72.766682 90)
		(property "Reference" "PR7069"
			(at 0 0 90)
			(layer "F.SilkS")
			(hide yes)
			(effects
				(font
					(size 1.27 1.27)
				)
			)
		)
		(property "Value" ""
			(at 0 0 90)
			(layer "F.Fab")
			(effects
				(font
					(size 1.27 1.27)
				)
			)
		)
		(duplicate_pad_numbers_are_jumpers no)
		(fp_line
			(start 0.7874 -0.4064)
			(end 0.7874 0.4064)
			(stroke
				(width 0.1524)
				(type default)
			)
			(layer "F.SilkS")
		)
		(fp_line
			(start -0.7874 -0.4064)
			(end 0.7874 -0.4064)
			(stroke
				(width 0.1524)
				(type default)
			)
			(layer "F.SilkS")
		)
		(fp_line
			(start 0.7874 0.4064)
			(end -0.7874 0.4064)
			(stroke
				(width 0.1524)
				(type default)
			)
			(layer "F.SilkS")
		)
		(fp_line
			(start -0.7874 0.4064)
			(end -0.7874 -0.4064)
			(stroke
				(width 0.1524)
				(type default)
			)
			(layer "F.SilkS")
		)
		(fp_line
			(start -0.12065 -0.305054)
			(end -0.12065 -0.2794)
			(stroke
				(width 0.1)
				(type default)
			)
			(layer "F.Fab")
		)
		(fp_line
			(start -0.67945 -0.305054)
			(end -0.12065 -0.305054)
			(stroke
				(width 0.1)
				(type default)
			)
			(layer "F.Fab")
		)
		(fp_line
			(start 0.67945 -0.3048)
			(end 0.67945 0.3048)
			(stroke
				(width 0.1)
				(type default)
			)
			(layer "F.Fab")
		)
		(fp_line
			(start 0.12065 -0.3048)
			(end 0.67945 -0.3048)
			(stroke
				(width 0.1)
				(type default)
			)
			(layer "F.Fab")
		)
		(fp_line
			(start 0.12065 -0.2794)
			(end 0.12065 -0.3048)
			(stroke
				(width 0.1)
				(type default)
			)
			(layer "F.Fab")
		)
		(fp_line
			(start -0.12065 -0.2794)
			(end 0.12065 -0.2794)
			(stroke
				(width 0.1)
				(type default)
			)
			(layer "F.Fab")
		)
		(fp_line
			(start 0.120396 0.2794)
			(end -0.12065 0.2794)
			(stroke
				(width 0.1)
				(type default)
			)
			(layer "F.Fab")
		)
		(fp_line
			(start -0.12065 0.2794)
			(end -0.12065 0.3048)
			(stroke
				(width 0.1)
				(type default)
			)
			(layer "F.Fab")
		)
		(fp_line
			(start 0.67945 0.3048)
			(end 0.120396 0.3048)
			(stroke
				(width 0.1)
				(type default)
			)
			(layer "F.Fab")
		)
		(fp_line
			(start 0.120396 0.3048)
			(end 0.120396 0.2794)
			(stroke
				(width 0.1)
				(type default)
			)
			(layer "F.Fab")
		)
		(fp_line
			(start -0.12065 0.3048)
			(end -0.67945 0.3048)
			(stroke
				(width 0.1)
				(type default)
			)
			(layer "F.Fab")
		)
		(fp_line
			(start -0.67945 0.3048)
			(end -0.67945 -0.305054)
			(stroke
				(width 0.1)
				(type default)
			)
			(layer "F.Fab")
		)
		(pad "1" smd circle
			(at -0.40005 0 90)
			(size 0 0)
			(layers "F.Cu" "F.Mask" "F.Paste")
			(net "P12V_SSD7_CO_MODE")
		)
		(pad "2" smd circle
			(at 0.40005 0 90)
			(size 0 0)
			(layers "F.Cu" "F.Mask" "F.Paste")
			(net "GND")
		)
	)
	(footprint ""
		(layer "F.Cu")
		(at 253.730506 -66.32194 -90)
		(property "Reference" "PC866"
			(at 0 0 270)
			(layer "F.SilkS")
			(hide yes)
			(effects
				(font
					(size 1.27 1.27)
				)
			)
		)
		(property "Value" ""
			(at 0 0 270)
			(layer "F.Fab")
			(effects
				(font
					(size 1.27 1.27)
				)
			)
		)
		(duplicate_pad_numbers_are_jumpers no)
		(fp_line
			(start -0.7874 0.4064)
			(end -0.7874 -0.4064)
			(stroke
				(width 0.1524)
				(type default)
			)
			(layer "F.SilkS")
		)
		(fp_line
			(start 0.7874 0.4064)
			(end -0.7874 0.4064)
			(stroke
				(width 0.1524)
				(type default)
			)
			(layer "F.SilkS")
		)
		(fp_line
			(start -0.7874 -0.4064)
			(end 0.7874 -0.4064)
			(stroke
				(width 0.1524)
				(type default)
			)
			(layer "F.SilkS")
		)
		(fp_line
			(start 0.7874 -0.4064)
			(end 0.7874 0.4064)
			(stroke
				(width 0.1524)
				(type default)
			)
			(layer "F.SilkS")
		)
		(fp_line
			(start -0.67945 0.3048)
			(end -0.67945 -0.305054)
			(stroke
				(width 0.1)
				(type default)
			)
			(layer "F.Fab")
		)
		(fp_line
			(start -0.12065 0.3048)
			(end -0.67945 0.3048)
			(stroke
				(width 0.1)
				(type default)
			)
			(layer "F.Fab")
		)
		(fp_line
			(start 0.120396 0.3048)
			(end 0.120396 0.2794)
			(stroke
				(width 0.1)
				(type default)
			)
			(layer "F.Fab")
		)
		(fp_line
			(start 0.67945 0.3048)
			(end 0.120396 0.3048)
			(stroke
				(width 0.1)
				(type default)
			)
			(layer "F.Fab")
		)
		(fp_line
			(start -0.12065 0.2794)
			(end -0.12065 0.3048)
			(stroke
				(width 0.1)
				(type default)
			)
			(layer "F.Fab")
		)
		(fp_line
			(start 0.120396 0.2794)
			(end -0.12065 0.2794)
			(stroke
				(width 0.1)
				(type default)
			)
			(layer "F.Fab")
		)
		(fp_line
			(start -0.12065 -0.2794)
			(end 0.12065 -0.2794)
			(stroke
				(width 0.1)
				(type default)
			)
			(layer "F.Fab")
		)
		(fp_line
			(start 0.12065 -0.2794)
			(end 0.12065 -0.3048)
			(stroke
				(width 0.1)
				(type default)
			)
			(layer "F.Fab")
		)
		(fp_line
			(start 0.12065 -0.3048)
			(end 0.67945 -0.3048)
			(stroke
				(width 0.1)
				(type default)
			)
			(layer "F.Fab")
		)
		(fp_line
			(start 0.67945 -0.3048)
			(end 0.67945 0.3048)
			(stroke
				(width 0.1)
				(type default)
			)
			(layer "F.Fab")
		)
		(fp_line
			(start -0.67945 -0.305054)
			(end -0.12065 -0.305054)
			(stroke
				(width 0.1)
				(type default)
			)
			(layer "F.Fab")
		)
		(fp_line
			(start -0.12065 -0.305054)
			(end -0.12065 -0.2794)
			(stroke
				(width 0.1)
				(type default)
			)
			(layer "F.Fab")
		)
		(pad "1" smd circle
			(at -0.40005 0 270)
			(size 0 0)
			(layers "F.Cu" "F.Mask" "F.Paste")
			(net "P12V_SSD8_CO_DV_DT")
		)
		(pad "2" smd circle
			(at 0.40005 0 270)
			(size 0 0)
			(layers "F.Cu" "F.Mask" "F.Paste")
			(net "GND")
		)
	)
	(footprint ""
		(layer "F.Cu")
		(at 384.54584 -258.463034)
		(property "Reference" "C3567"
			(at 0 0 0)
			(layer "F.SilkS")
			(hide yes)
			(effects
				(font
					(size 1.27 1.27)
				)
			)
		)
		(property "Value" ""
			(at 0 0 0)
			(layer "F.Fab")
			(effects
				(font
					(size 1.27 1.27)
				)
			)
		)
		(duplicate_pad_numbers_are_jumpers no)
		(fp_line
			(start -1.2954 -0.5842)
			(end 1.2954 -0.5842)
			(stroke
				(width 0.1524)
				(type default)
			)
			(layer "F.SilkS")
		)
		(fp_line
			(start -1.2954 0.5842)
			(end -1.2954 -0.5842)
			(stroke
				(width 0.1524)
				(type default)
			)
			(layer "F.SilkS")
		)
		(fp_line
			(start 1.2954 -0.5842)
			(end 1.2954 0.5842)
			(stroke
				(width 0.1524)
				(type default)
			)
			(layer "F.SilkS")
		)
		(fp_line
			(start 1.2954 0.5842)
			(end -1.2954 0.5842)
			(stroke
				(width 0.1524)
				(type default)
			)
			(layer "F.SilkS")
		)
		(fp_line
			(start -1.1938 -0.4064)
			(end -0.8636 -0.4064)
			(stroke
				(width 0.1)
				(type default)
			)
			(layer "F.Fab")
		)
		(fp_line
			(start -1.1938 0.4064)
			(end -1.1938 -0.4064)
			(stroke
				(width 0.1)
				(type default)
			)
			(layer "F.Fab")
		)
		(fp_line
			(start -0.8636 -0.4572)
			(end 0.8636 -0.4572)
			(stroke
				(width 0.1)
				(type default)
			)
			(layer "F.Fab")
		)
		(fp_line
			(start -0.8636 -0.4064)
			(end -0.8636 -0.4572)
			(stroke
				(width 0.1)
				(type default)
			)
			(layer "F.Fab")
		)
		(fp_line
			(start -0.8636 0.4064)
			(end -1.1938 0.4064)
			(stroke
				(width 0.1)
				(type default)
			)
			(layer "F.Fab")
		)
		(fp_line
			(start -0.8636 0.4572)
			(end -0.8636 0.4064)
			(stroke
				(width 0.1)
				(type default)
			)
			(layer "F.Fab")
		)
		(fp_line
			(start 0.8636 -0.4572)
			(end 0.8636 -0.4064)
			(stroke
				(width 0.1)
				(type default)
			)
			(layer "F.Fab")
		)
		(fp_line
			(start 0.8636 -0.4064)
			(end 1.1938 -0.4064)
			(stroke
				(width 0.1)
				(type default)
			)
			(layer "F.Fab")
		)
		(fp_line
			(start 0.8636 0.4064)
			(end 0.8636 0.4572)
			(stroke
				(width 0.1)
				(type default)
			)
			(layer "F.Fab")
		)
		(fp_line
			(start 0.8636 0.4572)
			(end -0.8636 0.4572)
			(stroke
				(width 0.1)
				(type default)
			)
			(layer "F.Fab")
		)
		(fp_line
			(start 1.1938 -0.4064)
			(end 1.1938 0.4064)
			(stroke
				(width 0.1)
				(type default)
			)
			(layer "F.Fab")
		)
		(fp_line
			(start 1.1938 0.4064)
			(end 0.8636 0.4064)
			(stroke
				(width 0.1)
				(type default)
			)
			(layer "F.Fab")
		)
		(pad "1" smd rect
			(at -0.7366 0 270)
			(size 0.7112 0.8128)
			(layers "F.Cu" "F.Mask" "F.Paste")
			(net "PCEPLL5_VDDA18_PEX3")
		)
		(pad "2" smd rect
			(at 0.7366 0 270)
			(size 0.7112 0.8128)
			(layers "F.Cu" "F.Mask" "F.Paste")
			(net "GND")
		)
	)
	(footprint ""
		(layer "F.Cu")
		(at 210.130136 -179.848256 -90)
		(property "Reference" "R5421"
			(at 0 0 270)
			(layer "F.SilkS")
			(hide yes)
			(effects
				(font
					(size 1.27 1.27)
				)
			)
		)
		(property "Value" ""
			(at 0 0 270)
			(layer "F.Fab")
			(effects
				(font
					(size 1.27 1.27)
				)
			)
		)
		(duplicate_pad_numbers_are_jumpers no)
		(fp_line
			(start -0.7874 0.4064)
			(end -0.7874 -0.4064)
			(stroke
				(width 0.1524)
				(type default)
			)
			(layer "F.SilkS")
		)
		(fp_line
			(start 0.7874 0.4064)
			(end -0.7874 0.4064)
			(stroke
				(width 0.1524)
				(type default)
			)
			(layer "F.SilkS")
		)
		(fp_line
			(start -0.7874 -0.4064)
			(end 0.7874 -0.4064)
			(stroke
				(width 0.1524)
				(type default)
			)
			(layer "F.SilkS")
		)
		(fp_line
			(start 0.7874 -0.4064)
			(end 0.7874 0.4064)
			(stroke
				(width 0.1524)
				(type default)
			)
			(layer "F.SilkS")
		)
		(fp_line
			(start -0.67945 0.3048)
			(end -0.67945 -0.305054)
			(stroke
				(width 0.1)
				(type default)
			)
			(layer "F.Fab")
		)
		(fp_line
			(start -0.12065 0.3048)
			(end -0.67945 0.3048)
			(stroke
				(width 0.1)
				(type default)
			)
			(layer "F.Fab")
		)
		(fp_line
			(start 0.120396 0.3048)
			(end 0.120396 0.2794)
			(stroke
				(width 0.1)
				(type default)
			)
			(layer "F.Fab")
		)
		(fp_line
			(start 0.67945 0.3048)
			(end 0.120396 0.3048)
			(stroke
				(width 0.1)
				(type default)
			)
			(layer "F.Fab")
		)
		(fp_line
			(start -0.12065 0.2794)
			(end -0.12065 0.3048)
			(stroke
				(width 0.1)
				(type default)
			)
			(layer "F.Fab")
		)
		(fp_line
			(start 0.120396 0.2794)
			(end -0.12065 0.2794)
			(stroke
				(width 0.1)
				(type default)
			)
			(layer "F.Fab")
		)
		(fp_line
			(start -0.12065 -0.2794)
			(end 0.12065 -0.2794)
			(stroke
				(width 0.1)
				(type default)
			)
			(layer "F.Fab")
		)
		(fp_line
			(start 0.12065 -0.2794)
			(end 0.12065 -0.3048)
			(stroke
				(width 0.1)
				(type default)
			)
			(layer "F.Fab")
		)
		(fp_line
			(start 0.12065 -0.3048)
			(end 0.67945 -0.3048)
			(stroke
				(width 0.1)
				(type default)
			)
			(layer "F.Fab")
		)
		(fp_line
			(start 0.67945 -0.3048)
			(end 0.67945 0.3048)
			(stroke
				(width 0.1)
				(type default)
			)
			(layer "F.Fab")
		)
		(fp_line
			(start -0.67945 -0.305054)
			(end -0.12065 -0.305054)
			(stroke
				(width 0.1)
				(type default)
			)
			(layer "F.Fab")
		)
		(fp_line
			(start -0.12065 -0.305054)
			(end -0.12065 -0.2794)
			(stroke
				(width 0.1)
				(type default)
			)
			(layer "F.Fab")
		)
		(pad "1" smd circle
			(at -0.40005 0 270)
			(size 0 0)
			(layers "F.Cu" "F.Mask" "F.Paste")
			(net "SEL_FLASH_PEX3_BUF_R")
		)
		(pad "2" smd circle
			(at 0.40005 0 270)
			(size 0 0)
			(layers "F.Cu" "F.Mask" "F.Paste")
			(net "P3V3_AUX")
		)
	)
	(footprint ""
		(layer "F.Cu")
		(at 134.366 -285.088584 90)
		(property "Reference" "PC90"
			(at 0 0 90)
			(layer "F.SilkS")
			(hide yes)
			(effects
				(font
					(size 1.27 1.27)
				)
			)
		)
		(property "Value" ""
			(at 0 0 90)
			(layer "F.Fab")
			(effects
				(font
					(size 1.27 1.27)
				)
			)
		)
		(duplicate_pad_numbers_are_jumpers no)
		(fp_line
			(start 0.7874 -0.4064)
			(end 0.7874 0.4064)
			(stroke
				(width 0.1524)
				(type default)
			)
			(layer "F.SilkS")
		)
		(fp_line
			(start -0.7874 -0.4064)
			(end 0.7874 -0.4064)
			(stroke
				(width 0.1524)
				(type default)
			)
			(layer "F.SilkS")
		)
		(fp_line
			(start 0.7874 0.4064)
			(end -0.7874 0.4064)
			(stroke
				(width 0.1524)
				(type default)
			)
			(layer "F.SilkS")
		)
		(fp_line
			(start -0.7874 0.4064)
			(end -0.7874 -0.4064)
			(stroke
				(width 0.1524)
				(type default)
			)
			(layer "F.SilkS")
		)
		(fp_line
			(start -0.12065 -0.305054)
			(end -0.12065 -0.2794)
			(stroke
				(width 0.1)
				(type default)
			)
			(layer "F.Fab")
		)
		(fp_line
			(start -0.67945 -0.305054)
			(end -0.12065 -0.305054)
			(stroke
				(width 0.1)
				(type default)
			)
			(layer "F.Fab")
		)
		(fp_line
			(start 0.67945 -0.3048)
			(end 0.67945 0.3048)
			(stroke
				(width 0.1)
				(type default)
			)
			(layer "F.Fab")
		)
		(fp_line
			(start 0.12065 -0.3048)
			(end 0.67945 -0.3048)
			(stroke
				(width 0.1)
				(type default)
			)
			(layer "F.Fab")
		)
		(fp_line
			(start 0.12065 -0.2794)
			(end 0.12065 -0.3048)
			(stroke
				(width 0.1)
				(type default)
			)
			(layer "F.Fab")
		)
		(fp_line
			(start -0.12065 -0.2794)
			(end 0.12065 -0.2794)
			(stroke
				(width 0.1)
				(type default)
			)
			(layer "F.Fab")
		)
		(fp_line
			(start 0.120396 0.2794)
			(end -0.12065 0.2794)
			(stroke
				(width 0.1)
				(type default)
			)
			(layer "F.Fab")
		)
		(fp_line
			(start -0.12065 0.2794)
			(end -0.12065 0.3048)
			(stroke
				(width 0.1)
				(type default)
			)
			(layer "F.Fab")
		)
		(fp_line
			(start 0.67945 0.3048)
			(end 0.120396 0.3048)
			(stroke
				(width 0.1)
				(type default)
			)
			(layer "F.Fab")
		)
		(fp_line
			(start 0.120396 0.3048)
			(end 0.120396 0.2794)
			(stroke
				(width 0.1)
				(type default)
			)
			(layer "F.Fab")
		)
		(fp_line
			(start -0.12065 0.3048)
			(end -0.67945 0.3048)
			(stroke
				(width 0.1)
				(type default)
			)
			(layer "F.Fab")
		)
		(fp_line
			(start -0.67945 0.3048)
			(end -0.67945 -0.305054)
			(stroke
				(width 0.1)
				(type default)
			)
			(layer "F.Fab")
		)
		(pad "1" smd circle
			(at -0.40005 0 90)
			(size 0 0)
			(layers "F.Cu" "F.Mask" "F.Paste")
			(net "P0V8_PEX1_PVCC")
		)
		(pad "2" smd circle
			(at 0.40005 0 90)
			(size 0 0)
			(layers "F.Cu" "F.Mask" "F.Paste")
			(net "GND")
		)
	)
)
